FILE_TYPE = CONNECTIVITY;
{Allegro Design Entry HDL 17.4-2019 S026 (4007227) 1/17/2022}
"PAGE_NUMBER" = 372;
0"NC";
1"GND\g";
2"GND\g";
3"GND\g";
4"GND\g";
5"GND\g";
6"AGND_HSC\g";
7"GND\g";
8"P12V_AUX\g";
9"GND\g";
10"P12V_AUX\g";
11"GND\g";
12"P3V3_AUX\g";
13"P12V_PSU\g";
14"GND\g";
15"P3V3_AUX\g";
16"GND\g";
17"P12V_AUX\g";
18"GND\g";
19"GND\g";
20"GND\g";
21"GND\g";
22"GND\g";
23"P3V3_AUX\g";
24"P3V3_AUX\g";
25"GND\g";
26"P12V_AUX\g";
27"GND\g";
28"GND\g";
29"P3V3_AUX\g";
30"GND\g";
31"GND\g";
32"GND\g";
33"P12V_AUX\g";
34"IRQ_UV_DETECT_N";
35"UV_P2V5_COMP";
36"P12V_AUX_UV_TRIGGER";
37"IRQ_UV_DETECT_N";
38"A_P12V_STBY_ADR_TRIGGER";
39"A_P12V_STBY_FP_TRIGGER";
40"IRQ_UV_DETECT_R2_N";
41"UV_ADR_P2V5_COMP";
42"P12V_AUX_UV_ADR_TRIGGER";
43"P12V_PSU_FUSE";
44"P12V_PSU_FUSE";
45"HSC_EN";
46"FM_UV_ADR_TRIGGER_N";
47"A_P12V_STBY_FPH_GATE";
48"SMB_SML1_PMBUS_HSC_R1_SDA";
49"SMB_SML1_PMBUS_HSC_R1_SCL";
50"U206_VS";
51"FM_UV_ADR_TRIGGER_N_R2";
52"FM_UV_ADR_TRIGGER_N";
53"PDB_PRSNT_R_N";
54"GND\g";
55"P12V_AUX\g";
56"P12V_AUX\g";
57"P3V3_AUX\g";
58"GND\g";
59"GND\g";
60"GND\g";
%"ZENER_AC"
"1","(-8575,5525)","1","pure_quanta","I1";
;
LOCATION"PD15"
$SEC"1"
CDS_SEC"1"
VALUE"5.0SMDJ14A"
PART_TYPE"SMLF"
MATERIAL"IC"
NEEDS_NO_SIZE"TRUE"
CDS_LMAN_SYM_OUTLINE"-75,50,75,-50"
CDS_LIB"pure_quanta"
PART_NUMBER"BC0MDJ14000";
"C"
$PN"C"43;
"A"
$PN"A"58;
%"Q_RES"
"2","(-7950,600)","0","pure_quanta","I10";
;
LOCATION"R3907"
$SEC"1"
CDS_SEC"1"
VALUE"33K"
TOLERANCE"1%"
WATTAGE"1/16W"
PACK_TYPE"0402LF"
MATERIAL"CHIP"
CDS_LIB"pure_quanta"
PART_NUMBER"CS33302FB00";
"A"
$PN"1"53;
"B"
$PN"2"60;
%"GND"
"1","(-6925,3350)","0","pure_quanta_power","I100";
;
SIZE"1B"
CDS_LIB"pure_quanta_power"
HDL_POWER"GND";
"A<SIZE-1..0>\NAC"1;
%"CONN3_210HP1030BR1"
"1","(-7850,3550)","2","pure_quanta","I103";
;
LOCATION"JP10"
$SEC"1"
CDS_SEC"1"
MATERIAL"IO"
PART_TYPE"THLF"
VALUE"CONN3_210-HP1-030BR1"
CDS_LIB"pure_quanta"
CDS_LMAN_SYM_OUTLINE"-50,100,50,-100"
NEEDS_NO_SIZE"TRUE"
PART_NUMBER"DFHD03MS213";
"1"
$PN"1"49;
"2"
$PN"2"48;
"3"
$PN"3"1;
%"Q_RES"
"2","(-650,2000)","0","pure_quanta","I104";
;
LOCATION"R8125"
$SEC"1"
CDS_SEC"1"
MATERIAL"CHIP"
PACK_TYPE"0402LF"
WATTAGE"1/16W"
TOLERANCE"1%"
VALUE"1K"
CDS_LIB"pure_quanta"
PART_NUMBER"CS21002FB06";
"A"
$PN"1"29;
"B"
$PN"2"34;
%"MOSFET_NCH_GDS_ESD_PROTECTED"
"1","(-7450,775)","0","pure_quanta","I11";
;
LOCATION"U290"
$SEC"1"
CDS_SEC"1"
PART_TYPE"SMLF"
MATERIAL"IC"
VALUE"2N7002K"
CDS_LMAN_SYM_OUTLINE"-125,150,125,-150"
CDS_LIB"pure_quanta"
NEEDS_NO_SIZE"TRUE"
PART_NUMBER"BAM70020002";
"S"
$PN"S"60;
"G"
$PN"G"53;
"D"
$PN"D"45;
%"GND"
"1","(-7425,325)","0","pure_quanta_power","I12";
;
ROOM"VR_DDR1_POWER_STAGE"
SIZE"1B"
CDS_LIB"pure_quanta_power"
HDL_POWER"GND";
"A<SIZE-1..0>\NAC"60;
%"Q_RES"
"2","(-6525,900)","0","pure_quanta","I13";
;
LOCATION"R2585"
$SEC"1"
CDS_SEC"1"
WATTAGE"1/16W"
PACK_TYPE"0402LF"
TOLERANCE"1%"
VALUE"31.6K"
MATERIAL"CHIP"
CDS_LIB"pure_quanta"
PART_NUMBER"CS33162FB02";
"A"
$PN"1"45;
"B"
$PN"2"2;
%"GND"
"1","(-6525,650)","0","pure_quanta_power","I14";
;
ROOM"VR_DDR1_POWER_STAGE"
CDS_LIB"pure_quanta_power"
SIZE"1B"
HDL_POWER"GND";
"A<SIZE-1..0>\NAC"2;
%"Q_RES"
"2","(-8000,1100)","0","pure_quanta","I16";
;
LOCATION"R3923"
$SEC"1"
CDS_SEC"1"
TOLERANCE"1%"
WATTAGE"1/16W"
VALUE"63.4K"
PACK_TYPE"0402LF"
CDS_LIB"pure_quanta"
MATERIAL"CHIP"
PART_NUMBER"CS36342FB04";
"A"
$PN"1"44;
"B"
$PN"2"53;
%"GND"
"1","(-8225,1750)","0","pure_quanta_power","I17";
;
ROOM"VR_DDR1_POWER_STAGE"
SIZE"1B"
CDS_LIB"pure_quanta_power"
HDL_POWER"GND";
"A<SIZE-1..0>\NAC"3;
%"CONN3_210HP1030BR1"
"1","(-7975,1950)","0","pure_quanta","I18";
;
LOCATION"JP4003"
$SEC"1"
CDS_SEC"1"
MATERIAL"IO"
PART_TYPE"THLF"
VALUE"CONN3_210-HP1-030BR1"
NEEDS_NO_SIZE"TRUE"
CDS_LMAN_SYM_OUTLINE"-50,100,50,-100"
CDS_LIB"pure_quanta"
PART_NUMBER"DFHD03MS213";
"1"
$PN"1"0;
"2"
$PN"2"53;
"3"
$PN"3"3;
%"Q_RES"
"1","(-6825,1500)","0","pure_quanta","I19";
;
LOCATION"R4901"
$SEC"1"
CDS_SEC"1"
VALUE"82K"
WATTAGE"1/16W"
TOLERANCE"1%"
MATERIAL"CHIP"
PACK_TYPE"0402LF"
CDS_LIB"pure_quanta"
PART_NUMBER"CS38202FB01";
"B"
$PN"2"45;
"A"
$PN"1"44;
%"Q_CAP"
"1","(-5900,1000)","0","pure_quanta","I22";
;
LOCATION"C2179"
SEC"1"
PACK_TYPE"C0402"
VOLTAGE"50V"
MATERIAL"X7R"
VALUE"100NF"
TOLERANCE"10%"
SEC_TYPE"C0402"
CDS_LIB"pure_quanta"
PART_NUMBER"CH4106K1B01";
"B"
$PN"2"4;
"A"
$PN"1"45;
%"UNIVERSAL_GND"
"1","(-5900,650)","0","pure_quanta_power","I24";
;
CDS_LIB"pure_quanta_power"
HDL_POWER"GND";
"A"4;
%"GND"
"1","(-8725,4650)","0","pure_quanta_power","I25";
;
CDS_LIB"pure_quanta_power"
SIZE"1B"
HDL_POWER"GND";
"A<SIZE-1..0>\NAC"5;
%"UNIVERSAL_GND"
"1","(-7950,4700)","0","pure_quanta_power","I26";
;
HDL_POWER"AGND_HSC"
CDS_LIB"pure_quanta_power";
"A"6;
%"Q_RES"
"1","(-8400,4900)","0","pure_quanta","I27";
;
LOCATION"PR3002"
$SEC"1"
CDS_SEC"1"
MATERIAL"CHIP"
VALUE"0"
TOLERANCE"5%"
WATTAGE"1/16W"
PACK_TYPE"0402LF"
CDS_LIB"pure_quanta"
PART_NUMBER"CS00002JB13";
"B"
$PN"2"6;
"A"
$PN"1"5;
%"UNIVERSAL_GND"
"1","(-6200,4500)","0","pure_quanta_power","I28";
;
CDS_LIB"pure_quanta_power"
HDL_POWER"GND";
"A"7;
%"Q_RES"
"2","(-6200,4800)","0","pure_quanta","I29";
;
LOCATION"R2227"
$SEC"1"
CDS_SEC"1"
WATTAGE"1/16W"
VALUE"10K"
TOLERANCE"1%"
PACK_TYPE"0402LF"
MATERIAL"EMPTY"
CDS_LIB"pure_quanta"
PART_NUMBER"CS31002FB08";
"A"
$PN"1"38;
"B"
$PN"2"7;
%"ZENER_AC"
"1","(-8075,5525)","1","pure_quanta","I3";
;
LOCATION"PD13"
$SEC"1"
CDS_SEC"1"
VALUE"5.0SMDJ14A"
MATERIAL"IC"
PART_TYPE"SMLF"
NEEDS_NO_SIZE"TRUE"
CDS_LIB"pure_quanta"
CDS_LMAN_SYM_OUTLINE"-75,50,75,-50"
PART_NUMBER"BC0MDJ14000";
"C"
$PN"C"43;
"A"
$PN"A"58;
%"Q_RES"
"2","(-6200,5550)","0","pure_quanta","I30";
;
LOCATION"R2219"
$SEC"1"
CDS_SEC"1"
TOLERANCE"1%"
WATTAGE"1/16W"
MATERIAL"EMPTY"
PACK_TYPE"0402LF"
VALUE"267K"
CDS_LIB"pure_quanta"
PART_NUMBER"CS42672FB03";
"A"
$PN"1"8;
"B"
$PN"2"38;
%"UNIVERSAL_POWER"
"1","(-6200,5900)","0","pure_quanta_power","I31";
;
HDL_POWER"P12V_AUX"
CDS_LIB"pure_quanta_power";
"A"8;
%"UNIVERSAL_GND"
"1","(-5600,4500)","0","pure_quanta_power","I32";
;
CDS_LIB"pure_quanta_power"
HDL_POWER"GND";
"A"9;
%"Q_RES"
"2","(-5600,4800)","0","pure_quanta","I33";
;
LOCATION"R2222"
$SEC"1"
CDS_SEC"1"
VALUE"1K"
PACK_TYPE"0402LF"
TOLERANCE"1%"
MATERIAL"EMPTY"
WATTAGE"1/16W"
CDS_LIB"pure_quanta"
PART_NUMBER"CS21002FB06";
"A"
$PN"1"39;
"B"
$PN"2"9;
%"Q_RES"
"2","(-5600,5550)","0","pure_quanta","I35";
;
LOCATION"R2221"
$SEC"1"
CDS_SEC"1"
TOLERANCE"1%"
VALUE"26.7K"
MATERIAL"EMPTY"
PACK_TYPE"0402LF"
WATTAGE"1/16W"
CDS_LIB"pure_quanta"
PART_NUMBER"CS32672FB03";
"A"
$PN"1"10;
"B"
$PN"2"39;
%"UNIVERSAL_POWER"
"1","(-5600,5900)","0","pure_quanta_power","I36";
;
HDL_POWER"P12V_AUX"
CDS_LIB"pure_quanta_power";
"A"10;
%"UNIVERSAL_GND"
"1","(-3375,4825)","0","pure_quanta_power","I39";
;
CDS_LIB"pure_quanta_power"
HDL_POWER"GND";
"A"59;
%"GND"
"1","(-7525,5275)","0","pure_quanta_power","I4";
;
ROOM"VR_DDR1_POWER_STAGE"
CDS_LIB"pure_quanta_power"
SIZE"1B"
HDL_POWER"GND";
"A<SIZE-1..0>\NAC"58;
%"UNIVERSAL_GND"
"1","(-1625,4775)","0","pure_quanta_power","I41";
;
CDS_LIB"pure_quanta_power"
HDL_POWER"GND";
"A"11;
%"MOSFET_N"
"1","(-1675,5150)","0","pure_quanta","I42";
;
LOCATION"U325"
$SEC"1"
CDS_SEC"1"
MATERIAL"EMPTY"
VALUE"BSS138K"
MANUF_PN"BSS138K"
CDS_LMAN_SYM_OUTLINE"-50,50,100,-150"
CDS_LIB"pure_quanta"
PACK_TYPE"SMLF"
PART_NUMBER"BAM138K0000";
"GATE"
$PN"G"47;
"SOURCE"
$PN"S"11;
"DRAIN"
$PN"D"37;
%"Q_RES"
"2","(-3275,5525)","0","pure_quanta","I43";
;
LOCATION"R2230"
$SEC"1"
CDS_SEC"1"
TOLERANCE"1%"
WATTAGE"1/16W"
MATERIAL"EMPTY"
PACK_TYPE"0402LF"
VALUE"10K"
CDS_LIB"pure_quanta"
PART_NUMBER"CS31002FB08";
"A"
$PN"1"57;
"B"
$PN"2"47;
%"UNIVERSAL_POWER"
"1","(-3275,5900)","0","pure_quanta_power","I44";
;
HDL_POWER"P3V3_AUX"
CDS_LIB"pure_quanta_power";
"A"57;
%"Q_RES"
"2","(-2975,5550)","0","pure_quanta","I45";
;
LOCATION"R2233"
$SEC"1"
CDS_SEC"1"
WATTAGE"1/16W"
TOLERANCE"1%"
MATERIAL"EMPTY"
VALUE"1K"
PACK_TYPE"0402LF"
CDS_LIB"pure_quanta"
PART_NUMBER"CS21002FB06";
"A"
$PN"1"57;
"B"
$PN"2"46;
%"Q_RES"
"2","(-1625,5725)","0","pure_quanta","I46";
;
LOCATION"R4620"
$SEC"1"
CDS_SEC"1"
WATTAGE"1/16W"
TOLERANCE"1%"
VALUE"1K"
PACK_TYPE"0402LF"
MATERIAL"EMPTY"
CDS_LIB"pure_quanta"
PART_NUMBER"CS21002FB06";
"A"
$PN"1"12;
"B"
$PN"2"37;
%"UNIVERSAL_POWER"
"1","(-1625,5950)","0","pure_quanta_power","I47";
;
HDL_POWER"P3V3_AUX"
CDS_LIB"pure_quanta_power";
"A"12;
%"LT6700CS61TRPBF"
"1","(-3825,5100)","0","pure_quanta","I49";
;
LOCATION"U206"
$SEC"1"
CDS_SEC"1"
MATERIAL"EMPTY"
PART_TYPE"SMLF"
VALUE"LT6700CS6-1#TRPBF"
CDS_LIB"pure_quanta"
CDS_LMAN_SYM_OUTLINE"-225,150,225,-150"
NEEDS_NO_SIZE"TRUE"
PART_NUMBER"AL006700001";
"OUTB"
$PN"6"47;
"INA+"
$PN"3"38;
"OUTA"
$PN"1"46;
"GND"
$PN"2"59;
"INB-"
$PN"4"39;
"VS"
$PN"5"50;
%"UNIVERSAL_POWER"
"1","(-8075,6150)","0","pure_quanta_power","I5";
;
HDL_POWER"P12V_PSU"
ROOM"AUX_SW"
BOM_COST"MIO_VRD_SB"
CDS_LIB"pure_quanta_power";
"A"13;
%"UNIVERSAL_GND"
"1","(-5475,2500)","0","pure_quanta_power","I50";
;
CDS_LIB"pure_quanta_power"
HDL_POWER"GND";
"A"14;
%"LM4040AIM3X25NOPB"
"1","(-5100,2825)","0","pure_quanta","I51";
;
LOCATION"U8007"
$SEC"1"
CDS_SEC"1"
VALUE"LM4040AIM3X-2.5/NOPB"
MATERIAL"IC"
PART_TYPE"SMLF"
CDS_LIB"pure_quanta"
PIN_NAMES_ROTATE"True"
CDS_LMAN_SYM_OUTLINE"-200,250,200,-250"
PART_NUMBER"AL404025013";
"3"
$PN"3"0;
"2-"
$PN"2"14;
"1+"
$PN"1"41;
%"Q_RES"
"2","(-5500,3650)","0","pure_quanta","I52";
;
LOCATION"R8113"
$SEC"1"
CDS_SEC"1"
PACK_TYPE"0402LF"
MATERIAL"CHIP"
WATTAGE"1/16W"
TOLERANCE"1%"
VALUE"10K"
CDS_LIB"pure_quanta"
PART_NUMBER"CS31002FB08";
"A"
$PN"1"15;
"B"
$PN"2"41;
%"UNIVERSAL_POWER"
"1","(-5500,3975)","0","pure_quanta_power","I53";
;
HDL_POWER"P3V3_AUX"
CDS_LIB"pure_quanta_power";
"A"15;
%"UNIVERSAL_GND"
"1","(-4500,2750)","0","pure_quanta_power","I54";
;
CDS_LIB"pure_quanta_power"
HDL_POWER"GND";
"A"16;
%"Q_RES"
"2","(-4500,3025)","0","pure_quanta","I55";
;
LOCATION"R8115"
$SEC"1"
CDS_SEC"1"
MATERIAL"CHIP"
VALUE"5.11K"
WATTAGE"1/16W"
TOLERANCE"1%"
PACK_TYPE"0402LF"
CDS_LIB"pure_quanta"
PART_NUMBER"CS25112FB04";
"A"
$PN"1"42;
"B"
$PN"2"16;
%"Q_RES"
"2","(-4500,3700)","0","pure_quanta","I56";
;
LOCATION"R8114"
$SEC"1"
CDS_SEC"1"
VALUE"17.8K"
WATTAGE"1/16W"
PACK_TYPE"0402LF"
TOLERANCE"1%"
MATERIAL"CHIP"
CDS_LIB"pure_quanta"
PART_NUMBER"CS31782FB04";
"A"
$PN"1"17;
"B"
$PN"2"42;
%"UNIVERSAL_POWER"
"1","(-4500,3950)","0","pure_quanta_power","I57";
;
HDL_POWER"P12V_AUX"
CDS_LIB"pure_quanta_power";
"A"17;
%"UNIVERSAL_GND"
"1","(-4100,2750)","0","pure_quanta_power","I58";
;
CDS_LIB"pure_quanta_power"
HDL_POWER"GND";
"A"18;
%"Q_CAP"
"1","(-4100,3025)","2","pure_quanta","I59";
;
LOCATION"C8017"
$SEC"1"
CDS_SEC"1"
PACK_TYPE"C0402"
MATERIAL"EMPTY"
VOLTAGE"50V"
TOLERANCE"10%"
VALUE"100NF"
CDS_LIB"pure_quanta"
PART_NUMBER"CH4106K1B01";
"B"
$PN"2"18;
"A"
$PN"1"41;
%"Q_FUSE"
"1","(-8075,5875)","3","pure_quanta","I6";
;
LOCATION"FS1"
$SEC"1"
CDS_SEC"1"
PACK_TYPE"SMLF"
VALUE"20A/125V"
MATERIAL"IC"
CDS_LIB"pure_quanta"
NEEDS_NO_SIZE"TRUE"
PART_NUMBER"DKK00XFU000";
"2 \B"
$PN"2"43;
"1 \B"
$PN"1"13;
%"UNIVERSAL_GND"
"1","(-3675,2750)","0","pure_quanta_power","I60";
;
CDS_LIB"pure_quanta_power"
HDL_POWER"GND";
"A"19;
%"Q_CAP"
"1","(-3675,3025)","2","pure_quanta","I61";
;
LOCATION"C8018"
$SEC"1"
CDS_SEC"1"
PACK_TYPE"C0402"
TOLERANCE"10%"
VALUE"100NF"
MATERIAL"EMPTY"
VOLTAGE"50V"
CDS_LIB"pure_quanta"
PART_NUMBER"CH4106K1B01";
"B"
$PN"2"19;
"A"
$PN"1"42;
%"UNIVERSAL_GND"
"1","(-3325,3000)","0","pure_quanta_power","I62";
;
CDS_LIB"pure_quanta_power"
HDL_POWER"GND";
"A"20;
%"Q_RES"
"1","(-2875,3750)","0","pure_quanta","I63";
;
LOCATION"R8117"
$SEC"1"
CDS_SEC"1"
MATERIAL"CHIP"
VALUE"1M"
TOLERANCE"1%"
WATTAGE"1/16W"
PACK_TYPE"0402LF"
CDS_LIB"pure_quanta"
PART_NUMBER"CS51002FB05";
"B"
$PN"2"51;
"A"
$PN"1"42;
%"UNIVERSAL_POWER"
"1","(-3325,4275)","0","pure_quanta_power","I64";
;
HDL_POWER"P12V_AUX"
CDS_LIB"pure_quanta_power";
"A"56;
%"UNIVERSAL_GND"
"1","(-3075,3850)","0","pure_quanta_power","I65";
;
CDS_LIB"pure_quanta_power"
HDL_POWER"GND";
"A"21;
%"Q_CAP"
"1","(-3075,4050)","2","pure_quanta","I66";
;
LOCATION"C8019"
$SEC"1"
CDS_SEC"1"
VOLTAGE"50V"
VALUE"100NF"
TOLERANCE"10%"
MATERIAL"X7R"
PACK_TYPE"C0402"
CDS_LIB"pure_quanta"
PART_NUMBER"CH4106K1B01";
"B"
$PN"2"21;
"A"
$PN"1"56;
%"Q_RES"
"1","(-1950,3425)","0","pure_quanta","I67";
;
LOCATION"R8118"
$SEC"1"
CDS_SEC"1"
TOLERANCE"1%"
VALUE"33.2"
MATERIAL"CHIP"
PACK_TYPE"0402LF"
WATTAGE"1/16W"
CDS_LIB"pure_quanta"
PART_NUMBER"CS03322FB03";
"B"
$PN"2"52;
"A"
$PN"1"51;
%"Q_RES"
"2","(-975,3700)","0","pure_quanta","I69";
;
LOCATION"R8119"
$SEC"1"
CDS_SEC"1"
VALUE"1K"
TOLERANCE"1%"
WATTAGE"1/16W"
PACK_TYPE"0402LF"
MATERIAL"CHIP"
CDS_LIB"pure_quanta"
PART_NUMBER"CS21002FB06";
"A"
$PN"1"23;
"B"
$PN"2"52;
%"UNIVERSAL_GND"
"1","(-8650,325)","0","pure_quanta_power","I7";
;
CDS_LIB"pure_quanta_power"
HDL_POWER"GND";
"A"22;
%"UNIVERSAL_POWER"
"1","(-975,4025)","0","pure_quanta_power","I70";
;
HDL_POWER"P3V3_AUX"
CDS_LIB"pure_quanta_power";
"A"23;
%"AP331AWG7"
"1","(-3325,3425)","0","pure_quanta","I71";
;
LOCATION"U8008"
$SEC"1"
CDS_SEC"1"
PART_TYPE"SMLF"
VALUE"AP331AWG-7"
MATERIAL"IC"
CDS_LMAN_SYM_OUTLINE"-100,100,100,-100"
NEEDS_NO_SIZE"TRUE"
CDS_LIB"pure_quanta"
PART_NUMBER"AL000331011";
"GND"
$PN"2"20;
"VCC"
$PN"5"56;
"OUTPUT"
$PN"4"51;
"IN-"
$PN"1"41;
"IN+"
$PN"3"42;
%"Q_RES"
"2","(-5175,1950)","0","pure_quanta","I72";
;
LOCATION"R8120"
$SEC"1"
CDS_SEC"1"
PACK_TYPE"0402LF"
VALUE"10K"
TOLERANCE"1%"
MATERIAL"CHIP"
WATTAGE"1/16W"
CDS_LIB"pure_quanta"
PART_NUMBER"CS31002FB08";
"A"
$PN"1"24;
"B"
$PN"2"35;
%"UNIVERSAL_POWER"
"1","(-5175,2275)","0","pure_quanta_power","I73";
;
HDL_POWER"P3V3_AUX"
CDS_LIB"pure_quanta_power";
"A"24;
%"UNIVERSAL_GND"
"1","(-4175,1050)","0","pure_quanta_power","I74";
;
CDS_LIB"pure_quanta_power"
HDL_POWER"GND";
"A"25;
%"Q_RES"
"2","(-4175,1325)","0","pure_quanta","I75";
;
LOCATION"R8122"
$SEC"1"
CDS_SEC"1"
WATTAGE"1/16W"
TOLERANCE"1%"
VALUE"5.11K"
PACK_TYPE"0402LF"
MATERIAL"CHIP"
CDS_LIB"pure_quanta"
PART_NUMBER"CS25112FB04";
"A"
$PN"1"36;
"B"
$PN"2"25;
%"Q_RES"
"2","(-4175,2000)","0","pure_quanta","I76";
;
LOCATION"R8121"
$SEC"1"
CDS_SEC"1"
PACK_TYPE"0402LF"
MATERIAL"CHIP"
WATTAGE"1/16W"
TOLERANCE"1%"
VALUE"17.8K"
CDS_LIB"pure_quanta"
PART_NUMBER"CS31782FB04";
"A"
$PN"1"26;
"B"
$PN"2"36;
%"UNIVERSAL_POWER"
"1","(-4175,2250)","0","pure_quanta_power","I77";
;
HDL_POWER"P12V_AUX"
CDS_LIB"pure_quanta_power";
"A"26;
%"UNIVERSAL_GND"
"1","(-3775,1050)","0","pure_quanta_power","I78";
;
CDS_LIB"pure_quanta_power"
HDL_POWER"GND";
"A"27;
%"Q_CAP"
"1","(-3775,1325)","2","pure_quanta","I79";
;
LOCATION"C8020"
$SEC"1"
CDS_SEC"1"
TOLERANCE"10%"
MATERIAL"EMPTY"
VOLTAGE"50V"
VALUE"100NF"
PACK_TYPE"C0402"
CDS_LIB"pure_quanta"
PART_NUMBER"CH4106K1B01";
"B"
$PN"2"27;
"A"
$PN"1"35;
%"AP331AWG7"
"1","(-3000,1725)","0","pure_quanta","I80";
;
LOCATION"U8010"
$SEC"1"
CDS_SEC"1"
MATERIAL"IC"
VALUE"AP331AWG-7"
PART_TYPE"SMLF"
CDS_LIB"pure_quanta"
NEEDS_NO_SIZE"TRUE"
CDS_LMAN_SYM_OUTLINE"-100,100,100,-100"
PART_NUMBER"AL000331011";
"GND"
$PN"2"32;
"VCC"
$PN"5"55;
"OUTPUT"
$PN"4"40;
"IN-"
$PN"1"35;
"IN+"
$PN"3"36;
%"Q_RES"
"1","(-2550,2050)","0","pure_quanta","I81";
;
LOCATION"R8123"
$SEC"1"
CDS_SEC"1"
VALUE"1M"
WATTAGE"1/16W"
PACK_TYPE"0402LF"
MATERIAL"CHIP"
TOLERANCE"1%"
CDS_LIB"pure_quanta"
PART_NUMBER"CS51002FB05";
"B"
$PN"2"40;
"A"
$PN"1"36;
%"UNIVERSAL_GND"
"1","(-2750,2150)","0","pure_quanta_power","I82";
;
CDS_LIB"pure_quanta_power"
HDL_POWER"GND";
"A"28;
%"UNIVERSAL_POWER"
"1","(-3000,2575)","0","pure_quanta_power","I83";
;
HDL_POWER"P12V_AUX"
CDS_LIB"pure_quanta_power";
"A"55;
%"Q_CAP"
"1","(-2750,2350)","2","pure_quanta","I84";
;
LOCATION"C8022"
$SEC"1"
CDS_SEC"1"
MATERIAL"X7R"
TOLERANCE"10%"
VOLTAGE"50V"
VALUE"100NF"
PACK_TYPE"C0402"
CDS_LIB"pure_quanta"
PART_NUMBER"CH4106K1B01";
"B"
$PN"2"28;
"A"
$PN"1"55;
%"Q_RES"
"1","(-1625,1725)","0","pure_quanta","I85";
;
LOCATION"R8124"
$SEC"1"
CDS_SEC"1"
TOLERANCE"1%"
VALUE"33.2"
MATERIAL"CHIP"
CDS_LIB"pure_quanta"
WATTAGE"1/16W"
PACK_TYPE"0402LF"
PART_NUMBER"CS03322FB03";
"B"
$PN"2"34;
"A"
$PN"1"40;
%"UNIVERSAL_POWER"
"1","(-650,2325)","0","pure_quanta_power","I88";
;
HDL_POWER"P3V3_AUX"
CDS_LIB"pure_quanta_power";
"A"29;
%"UNIVERSAL_GND"
"1","(-5150,800)","0","pure_quanta_power","I89";
;
CDS_LIB"pure_quanta_power"
HDL_POWER"GND";
"A"30;
%"Q_CAP"
"1","(-8650,550)","0","pure_quanta","I9";
;
LOCATION"C1797"
$SEC"1"
CDS_SEC"1"
VALUE"0.1UF"
TOLERANCE"10%"
VOLTAGE"25V"
MATERIAL"X7R"
PACK_TYPE"0402"
CDS_LIB"pure_quanta"
PART_NUMBER"CH4104K1B00";
"B"
$PN"2"22;
"A"
$PN"1"53;
%"UNIVERSAL_GND"
"1","(-3350,1050)","0","pure_quanta_power","I90";
;
CDS_LIB"pure_quanta_power"
HDL_POWER"GND";
"A"31;
%"UNIVERSAL_GND"
"1","(-3000,1300)","0","pure_quanta_power","I91";
;
CDS_LIB"pure_quanta_power"
HDL_POWER"GND";
"A"32;
%"Q_CAP"
"1","(-3350,1325)","2","pure_quanta","I92";
;
LOCATION"C8021"
$SEC"1"
CDS_SEC"1"
VALUE"100NF"
VOLTAGE"50V"
TOLERANCE"10%"
PACK_TYPE"C0402"
MATERIAL"EMPTY"
CDS_LIB"pure_quanta"
PART_NUMBER"CH4106K1B01";
"B"
$PN"2"31;
"A"
$PN"1"36;
%"LM4040AIM3X25NOPB"
"1","(-4775,1125)","0","pure_quanta","I93";
;
LOCATION"U8009"
$SEC"1"
CDS_SEC"1"
PART_TYPE"SMLF"
MATERIAL"IC"
VALUE"LM4040AIM3X-2.5/NOPB"
CDS_LMAN_SYM_OUTLINE"-200,250,200,-250"
PIN_NAMES_ROTATE"True"
CDS_LIB"pure_quanta"
PART_NUMBER"AL404025013";
"3"
$PN"3"0;
"2-"
$PN"2"30;
"1+"
$PN"1"35;
%"UNIVERSAL_GND"
"1","(-5050,5300)","0","pure_quanta_power","I95";
;
CDS_LIB"pure_quanta_power"
HDL_POWER"GND";
"A"54;
%"Q_CAP"
"1","(-5050,5550)","0","pure_quanta","I96";
;
LOCATION"C1561"
$SEC"1"
CDS_SEC"1"
TOLERANCE"10%"
VALUE"0.1UF"
PACK_TYPE"0402"
MATERIAL"EMPTY"
VOLTAGE"25V"
CDS_LIB"pure_quanta"
PART_NUMBER"CH4104K1B00";
"B"
$PN"2"54;
"A"
$PN"1"50;
%"Q_RES"
"2","(-4650,5925)","0","pure_quanta","I97";
;
LOCATION"R9021"
$SEC"1"
CDS_SEC"1"
TOLERANCE"1%"
MATERIAL"EMPTY"
VALUE"1K"
WATTAGE"1/16W"
PACK_TYPE"0402LF"
CDS_LIB"pure_quanta"
PART_NUMBER"CS21002FB06";
"A"
$PN"1"33;
"B"
$PN"2"50;
%"UNIVERSAL_POWER"
"1","(-4650,6175)","0","pure_quanta_power","I98";
;
HDL_POWER"P12V_AUX"
CDS_LIB"pure_quanta_power";
"A"33;
%"Q_CAP"
"1","(-4650,5525)","2","pure_quanta","I99";
;
LOCATION"C9004"
$SEC"1"
CDS_SEC"1"
PACK_TYPE"C0402"
VOLTAGE"25V"
VALUE"1UF"
MATERIAL"EMPTY"
TOLERANCE"10%"
CDS_LIB"pure_quanta"
PART_NUMBER"CH5104KEB02";
"B"
$PN"2"54;
"A"
$PN"1"50;
END.
